#ISCELL
  mstr_misc dns *
  *
#ISCELL
  pure_quanta quanta_title_block_c *
  *
#ISCELL
  logical_power universal_gnd *
  page257_i1
#ISCELL
  logical_power vcc15 *
  page257_i10
#ISCELL
  standard offpage *
  page257_i11
#ISCELL
  standard offpage *
  page257_i12
#ISCELL
  standard offpage *
  page257_i13
#ISCELL
  standard offpage *
  page257_i14
#CELL
  pure_quanta q_cap *
  page257_i15
#CELL
  pure_quanta isl99390frztr5935 *
  page257_i16
#ISCELL
  logical_power universal_gnd *
  page257_i17
#CELL
  pure_quanta q_cap *
  page257_i18
#CELL
  pure_quanta q_res *
  page257_i19
#CELL
  pure_quanta q_res *
  page257_i2
#ISCELL
  logical_power universal_gnd *
  page257_i20
#CELL
  pure_quanta q_cap *
  page257_i21
#CELL
  pure_quanta q_res *
  page257_i22
#ISCELL
  logical_power vcc15 *
  page257_i23
#ISCELL
  standard offpage *
  page257_i24
#CELL
  pure_quanta isl99390frztr5935 *
  page257_i25
#ISCELL
  logical_power universal_gnd *
  page257_i26
#CELL
  pure_quanta q_cap *
  page257_i27
#CELL
  pure_quanta q_cap *
  page257_i28
#ISCELL
  logical_power universal_gnd *
  page257_i29
#ISCELL
  logical_power universal_gnd *
  page257_i3
#CELL
  pure_quanta q_res *
  page257_i30
#CELL
  pure_quanta q_cap *
  page257_i31
#CELL
  pure_quanta q_cap *
  page257_i32
#ISCELL
  standard offpage *
  page257_i33
#ISCELL
  standard offpage *
  page257_i34
#CELL
  pure_quanta q_cap *
  page257_i35
#ISCELL
  standard offpage *
  page257_i36
#CELL
  pure_quanta q_cap *
  page257_i37
#ISCELL
  logical_power universal_gnd *
  page257_i38
#CELL
  pure_quanta q_res *
  page257_i39
#CELL
  pure_quanta q_res *
  page257_i4
#CELL
  pure_quanta q_res *
  page257_i40
#ISCELL
  logical_power universal_gnd *
  page257_i41
#CELL
  pure_quanta q_cap *
  page257_i42
#ISCELL
  logical_power vcc15 *
  page257_i43
#CELL
  pure_quanta q_cap *
  page257_i44
#CELL
  pure_quanta q_cap *
  page257_i45
#CELL
  pure_quanta q_res *
  page257_i46
#CELL
  pure_quanta q_cap *
  page257_i47
#CELL
  pure_quanta q_cap *
  page257_i48
#CELL
  pure_quanta q_inductor *
  page257_i49
#ISCELL
  logical_power vcc15 *
  page257_i5
#CELL
  pure_quanta q_res *
  page257_i50
#CELL
  pure_quanta q_cap *
  page257_i51
#CELL
  pure_quanta q_cap *
  page257_i52
#CELL
  pure_quanta q_cap *
  page257_i53
#ISCELL
  logical_power universal_gnd *
  page257_i54
#CELL
  pure_quanta q_cap *
  page257_i55
#ISCELL
  logical_power vcc15 *
  page257_i56
#CELL
  pure_quanta q_capp *
  page257_i57
#CELL
  pure_quanta q_capp *
  page257_i58
#CELL
  pure_quanta q_cap *
  page257_i59
#ISCELL
  logical_power universal_gnd *
  page257_i6
#CELL
  pure_quanta q_res *
  page257_i60
#ISCELL
  logical_power universal_gnd *
  page257_i61
#CELL
  pure_quanta q_capp *
  page257_i62
#CELL
  pure_quanta q_capp *
  page257_i63
#ISCELL
  logical_power universal_gnd *
  page257_i64
#ISCELL
  logical_power vcc15 *
  page257_i65
#ISCELL
  logical_power universal_gnd *
  page257_i66
#CELL
  pure_quanta q_capp *
  page257_i67
#ISCELL
  logical_power vcc15 *
  page257_i68
#CELL
  pure_quanta q_res *
  page257_i69
#ISCELL
  logical_power universal_gnd *
  page257_i7
#CELL
  pure_quanta q_inductor *
  page257_i70
#CELL
  pure_quanta q_cap *
  page257_i71
#ISCELL
  logical_power universal_gnd *
  page257_i72
#CELL
  pure_quanta q_cap *
  page257_i73
#ISCELL
  logical_power vcc15 *
  page257_i74
#CELL
  pure_quanta q_cap *
  page257_i75
#ISCELL
  logical_power gnd *
  page257_i76
#CELL
  pure_quanta q_cap *
  page257_i77
#CELL
  pure_quanta q_cap *
  page257_i78
#ISCELL
  logical_power vcc15 *
  page257_i79
#CELL
  pure_quanta q_res *
  page257_i8
#CELL
  pure_quanta q_inductor *
  page257_i80
#CELL
  pure_quanta q_cap *
  page257_i81
#ISCELL
  logical_power vcc15 *
  page257_i82
#CELL
  pure_quanta q_cap *
  page257_i83
#CELL
  pure_quanta q_cap *
  page257_i84
#CELL
  pure_quanta q_cap *
  page257_i85
#CELL
  pure_quanta q_cap *
  page257_i86
#ISCELL
  logical_power universal_gnd *
  page257_i87
#CELL
  pure_quanta q_capp *
  page257_i88
#ISCELL
  logical_power vcc15 *
  page257_i89
#CELL
  pure_quanta q_res *
  page257_i9
